FILE_TYPE=LIBRARY_PARTS;
TIME=' Created/Modified on Fri Dec 28 16:05:44 2007' ;
primitive 'Q_OSC4P';
  pin
    'OE':
      PIN_NUMBER='(1)';
      INPUT_LOAD='(-0.01,0.01)';
    'OUT':
      PIN_NUMBER='(3)';
      OUTPUT_LOAD='(1.0,-1.0)';
    'GND':
      PIN_NUMBER='(2)';
      PINUSE='POWER';
    'VDD':
      PIN_NUMBER='(4)';
      PINUSE='POWER';
  end_pin;
  body
    CLASS='DISCRETE';
    PART_NAME='Q_OSC4P';
    PHYS_DES_PREFIX='OSC';
  end_body;
end_primitive;
END.
